G04 ================== begin FILE IDENTIFICATION RECORD ==================*
G04 Layout Name:  t6mg_pdb_a_v02_0109_1330.brd*
G04 Film Name:    outline*
G04 File Format:  Gerber RS274X*
G04 File Origin:  Cadence Allegro 16.3-S038*
G04 Origin Date:  Mon Jan 13 14:11:54 2014*
G04 *
G04 Layer:  BOARD GEOMETRY/OUTLINE*
G04 *
G04 Offset:    (0.00 0.00)*
G04 Mirror:    No*
G04 Mode:      Positive*
G04 Rotation:  0*
G04 FullContactRelief:  No*
G04 UndefLineWidth:     6.00*
G04 ================== end FILE IDENTIFICATION RECORD ====================*
%FSLAX25Y25*MOIN*%
%IR0*IPPOS*OFA0.00000B0.00000*MIA0B0*SFA1.00000B1.00000*%
%ADD10C,.006*%
G75*
%LPD*%
G75*
G54D10*
G01X397638Y0D02*
G03X405512Y7874I0J7874D01*
G01Y2078740D01*
G03X397638Y2086614I-7874J0D01*
G01X104331D01*
G03X98425Y2080709I-1J-5905D01*
G01Y2076772D01*
G02X92520Y2070866I-5906J0D01*
G01X5906D01*
G03X0Y2064961I-1J-5905D01*
G01Y21654D01*
G03X5906Y15748I5906J0D01*
G01X92520D01*
G02X98425Y9843I0J-5905D01*
G01Y5906D01*
G03X104331Y0I5906J0D01*
G01X397638D01*
G01X317323Y1881102D02*
G02X296850I-10237J0D01*
G01Y1885039D01*
G02X317323I10236J0D01*
G01Y1881102D01*
G01Y1885039D02*
Y1881102D01*
G02X296850I-10237J0D01*
G01Y1885039D01*
G02X317323I10236J0D01*
M02*
